(kicad_pcb
	(version 20241229)
	(generator "pcbnew")
	(generator_version "9.0")
	(general
		(thickness 1.61)
		(legacy_teardrops no)
	)
	(paper "A3")
	(title_block
		(title "RDIMM DDR5 Tester")
		(date "2026-05-21")
		(rev "2.2.0")
		(company "Antmicro")
		(comment 9 "footprints 789-793 of 796")
	)
	(layers
		(0 "F.Cu" signal)
		(4 "In1.Cu" power)
		(6 "In2.Cu" mixed)
		(8 "In3.Cu" power)
		(10 "In4.Cu" mixed)
		(12 "In5.Cu" power)
		(14 "In6.Cu" mixed)
		(16 "In7.Cu" power)
		(18 "In8.Cu" power)
		(20 "In9.Cu" mixed)
		(22 "In10.Cu" power)
		(2 "B.Cu" signal)
		(9 "F.Adhes" user "F.Adhesive")
		(11 "B.Adhes" user "B.Adhesive")
		(13 "F.Paste" user)
		(15 "B.Paste" user)
		(5 "F.SilkS" user "F.Silkscreen")
		(7 "B.SilkS" user "B.Silkscreen")
		(1 "F.Mask" user)
		(3 "B.Mask" user)
		(17 "Dwgs.User" user "User.Drawings")
		(19 "Cmts.User" user "User.Comments")
		(21 "Eco1.User" user "User.Eco1")
		(23 "Eco2.User" user "User.Eco2")
		(25 "Edge.Cuts" user)
		(27 "Margin" user)
		(31 "F.CrtYd" user "F.Courtyard")
		(29 "B.CrtYd" user "B.Courtyard")
		(35 "F.Fab" user)
		(33 "B.Fab" user)
	)
	(footprint "antmicro-footprints:C_0402_1005Metric"
		(layer "B.Cu")
		(at 194.672499 193.2285 90)
		(descr "Capacitor SMD 0402")
		(tags "capacitor SMD 0402")
		(property "Reference" "C252"
			(at 0.994 0.403501 90)
			(layer "B.SilkS")
			(effects
				(font
					(size 0.7 0.7)
					(thickness 0.15)
				)
				(justify right bottom mirror)
			)
		)
		(property "Value" "C_100n_0402"
			(at -1.022927 -2.155213 90)
			(layer "B.Fab")
			(effects
				(font
					(size 0.7 0.7)
					(thickness 0.15)
				)
				(justify right bottom mirror)
			)
		)
		(property "Datasheet" "https://www.murata.com/products/productdetail?partno=GRM155R61H104KE14%23"
			(at 0 0 90)
			(layer "F.Fab")
			(hide yes)
			(effects
				(font
					(size 1.27 1.27)
					(thickness 0.15)
				)
			)
		)
		(property "Manufacturer" "Murata"
			(at 0 0 90)
			(unlocked yes)
			(layer "B.Fab")
			(hide yes)
			(effects
				(font
					(size 1 1)
					(thickness 0.15)
				)
				(justify mirror)
			)
		)
		(property "MPN" "GRM155R61H104KE14D"
			(at 0 0 90)
			(unlocked yes)
			(layer "B.Fab")
			(hide yes)
			(effects
				(font
					(size 1 1)
					(thickness 0.15)
				)
				(justify mirror)
			)
		)
		(property "Val" "100n"
			(at 0 0 90)
			(unlocked yes)
			(layer "B.Fab")
			(hide yes)
			(effects
				(font
					(size 1 1)
					(thickness 0.15)
				)
				(justify mirror)
			)
		)
		(property "License" "Apache-2.0"
			(at 0 0 90)
			(unlocked yes)
			(layer "B.Fab")
			(hide yes)
			(effects
				(font
					(size 1 1)
					(thickness 0.15)
				)
				(justify mirror)
			)
		)
		(property "Author" "Antmicro"
			(at 0 0 90)
			(unlocked yes)
			(layer "B.Fab")
			(hide yes)
			(effects
				(font
					(size 1 1)
					(thickness 0.15)
				)
				(justify mirror)
			)
		)
		(property "Voltage" "50V"
			(at 0 0 90)
			(unlocked yes)
			(layer "B.Fab")
			(hide yes)
			(effects
				(font
					(size 1 1)
					(thickness 0.15)
				)
				(justify mirror)
			)
		)
		(property "Dielectric" "X5R"
			(at 0 0 90)
			(unlocked yes)
			(layer "B.Fab")
			(hide yes)
			(effects
				(font
					(size 1 1)
					(thickness 0.15)
				)
				(justify mirror)
			)
		)
		(sheetname "/FPGA MGT Interface/")
		(sheetfile "fpga-mgt.kicad_sch")
		(attr smd)
		(fp_rect
			(start -0.925 0.47)
			(end 0.925 -0.47)
			(stroke
				(width 0.05)
				(type default)
			)
			(fill no)
			(layer "B.CrtYd")
		)
		(fp_line
			(start 0.504 -0.248)
			(end -0.494 -0.248)
			(stroke
				(width 0.15)
				(type solid)
			)
			(layer "B.Fab")
		)
		(fp_line
			(start -0.494 -0.248)
			(end -0.494 0.25)
			(stroke
				(width 0.15)
				(type solid)
			)
			(layer "B.Fab")
		)
		(fp_line
			(start 0.504 0.25)
			(end 0.504 -0.248)
			(stroke
				(width 0.15)
				(type solid)
			)
			(layer "B.Fab")
		)
		(fp_line
			(start -0.494 0.25)
			(end 0.504 0.25)
			(stroke
				(width 0.15)
				(type solid)
			)
			(layer "B.Fab")
		)
		(fp_text user "${REFERENCE}"
			(at -0.939 -4.599 270)
			(layer "B.Fab")
			(effects
				(font
					(size 0.7 0.7)
					(thickness 0.15)
				)
				(justify left bottom mirror)
			)
		)
		(fp_text user "License: Apache-2.0"
			(at -0.939 -5.799 270)
			(layer "B.Fab")
			(effects
				(font
					(size 0.7 0.7)
					(thickness 0.15)
				)
				(justify left bottom mirror)
			)
		)
		(fp_text user "Author: Antmicro"
			(at -0.939 -3.399 270)
			(layer "B.Fab")
			(effects
				(font
					(size 0.7 0.7)
					(thickness 0.15)
				)
				(justify left bottom mirror)
			)
		)
		(pad "1" smd roundrect
			(at -0.48 0 90)
			(size 0.59 0.64)
			(layers "B.Cu" "B.Mask" "B.Paste")
			(roundrect_rratio 0.25)
			(net 254 "/FPGA MGT Interface/PCIE.TXD7_N")
			(pintype "passive")
		)
		(pad "2" smd roundrect
			(at 0.48 0 90)
			(size 0.59 0.64)
			(layers "B.Cu" "B.Mask" "B.Paste")
			(roundrect_rratio 0.25)
			(net 558 "/FPGA MGT Interface/GTY_224_TX0_N")
			(pintype "passive")
		)
	)
	(footprint "antmicro-footprints:R_0402_1005Metric"
		(layer "B.Cu")
		(at 231.685 183.97)
		(descr "Resistor SMD 0402")
		(tags "resistor SMD 0402")
		(property "Reference" "R199"
			(at -1.815 -1.555 0)
			(layer "B.SilkS")
			(effects
				(font
					(size 0.7 0.7)
					(thickness 0.15)
				)
				(justify right bottom mirror)
			)
		)
		(property "Value" "R_15k_0402"
			(at -1.011843 -1.772047 0)
			(layer "B.Fab")
			(effects
				(font
					(size 0.7 0.7)
					(thickness 0.15)
				)
				(justify right bottom mirror)
			)
		)
		(property "Datasheet" "https://www.bourns.com/docs/product-datasheets/cr.pdf"
			(at 0 0 0)
			(layer "F.Fab")
			(hide yes)
			(effects
				(font
					(size 1.27 1.27)
					(thickness 0.15)
				)
			)
		)
		(property "MPN" "CR0402-FX-1502GLF"
			(at 0 0 0)
			(unlocked yes)
			(layer "B.Fab")
			(hide yes)
			(effects
				(font
					(size 1 1)
					(thickness 0.15)
				)
				(justify mirror)
			)
		)
		(property "Manufacturer" "Bourns"
			(at 0 0 0)
			(unlocked yes)
			(layer "B.Fab")
			(hide yes)
			(effects
				(font
					(size 1 1)
					(thickness 0.15)
				)
				(justify mirror)
			)
		)
		(property "License" "Apache-2.0"
			(at 0 0 0)
			(unlocked yes)
			(layer "B.Fab")
			(hide yes)
			(effects
				(font
					(size 1 1)
					(thickness 0.15)
				)
				(justify mirror)
			)
		)
		(property "Author" "Antmicro"
			(at 0 0 0)
			(unlocked yes)
			(layer "B.Fab")
			(hide yes)
			(effects
				(font
					(size 1 1)
					(thickness 0.15)
				)
				(justify mirror)
			)
		)
		(property "Val" "15k"
			(at 0 0 0)
			(unlocked yes)
			(layer "B.Fab")
			(hide yes)
			(effects
				(font
					(size 1 1)
					(thickness 0.15)
				)
				(justify mirror)
			)
		)
		(property "Tolerance" "1%"
			(at 0 0 0)
			(unlocked yes)
			(layer "B.Fab")
			(hide yes)
			(effects
				(font
					(size 1 1)
					(thickness 0.15)
				)
				(justify mirror)
			)
		)
		(sheetname "/Supply/DC-DC VCCINT/")
		(sheetfile "dc-dc-vccint.kicad_sch")
		(attr smd)
		(fp_rect
			(start -0.925 0.47)
			(end 0.925 -0.47)
			(stroke
				(width 0.05)
				(type default)
			)
			(fill no)
			(layer "B.CrtYd")
		)
		(fp_rect
			(start -0.5 0.25)
			(end 0.5 -0.25)
			(stroke
				(width 0.15)
				(type solid)
			)
			(fill no)
			(layer "B.Fab")
		)
		(fp_text user "Author: Antmicro"
			(at -0.95 -4.169 180)
			(layer "B.Fab")
			(effects
				(font
					(size 0.7 0.7)
					(thickness 0.15)
				)
				(justify left bottom mirror)
			)
		)
		(fp_text user "${REFERENCE}"
			(at -0.95 -3.168 180)
			(layer "B.Fab")
			(effects
				(font
					(size 0.7 0.7)
					(thickness 0.15)
				)
				(justify left bottom mirror)
			)
		)
		(fp_text user "License: Apache-2.0"
			(at -0.95 -5.169 180)
			(layer "B.Fab")
			(effects
				(font
					(size 0.7 0.7)
					(thickness 0.15)
				)
				(justify left bottom mirror)
			)
		)
		(pad "1" smd roundrect
			(at -0.48 0)
			(size 0.59 0.64)
			(layers "B.Cu" "B.Mask" "B.Paste")
			(roundrect_rratio 0.25)
			(net 1 "GND")
			(pintype "passive")
		)
		(pad "2" smd roundrect
			(at 0.48 0)
			(size 0.59 0.64)
			(layers "B.Cu" "B.Mask" "B.Paste")
			(roundrect_rratio 0.25)
			(net 728 "Net-(U36-ADDR)")
			(pintype "passive")
		)
	)
	(footprint "antmicro-footprints:TP_SMD_1mm"
		(layer "B.Cu")
		(at 233.35 184.725 90)
		(property "Reference" "TP26"
			(at -0.725 0.7 180)
			(layer "B.SilkS")
			(effects
				(font
					(size 0.7 0.7)
					(thickness 0.15)
				)
				(justify right bottom mirror)
			)
		)
		(property "Value" "TP_1mm_SMD"
			(at 0 -1.4 90)
			(layer "B.Fab")
			(effects
				(font
					(size 0.7 0.7)
					(thickness 0.15)
				)
				(justify right bottom mirror)
			)
		)
		(property "MPN" ""
			(at 0 0 90)
			(unlocked yes)
			(layer "B.Fab")
			(hide yes)
			(effects
				(font
					(size 1 1)
					(thickness 0.15)
				)
				(justify mirror)
			)
		)
		(property "Manufacturer" ""
			(at 0 0 90)
			(unlocked yes)
			(layer "B.Fab")
			(hide yes)
			(effects
				(font
					(size 1 1)
					(thickness 0.15)
				)
				(justify mirror)
			)
		)
		(property "Author" "Antmicro"
			(at 0 0 90)
			(unlocked yes)
			(layer "B.Fab")
			(hide yes)
			(effects
				(font
					(size 1 1)
					(thickness 0.15)
				)
				(justify mirror)
			)
		)
		(property "License" "Apache-2.0"
			(at 0 0 90)
			(unlocked yes)
			(layer "B.Fab")
			(hide yes)
			(effects
				(font
					(size 1 1)
					(thickness 0.15)
				)
				(justify mirror)
			)
		)
		(sheetname "/Supply/DC-DC VCCINT/")
		(sheetfile "dc-dc-vccint.kicad_sch")
		(attr exclude_from_pos_files)
		(fp_circle
			(center 0 0)
			(end 0.6 0)
			(stroke
				(width 0.05)
				(type default)
			)
			(fill no)
			(layer "B.CrtYd")
		)
		(fp_text user "License: Apache-2.0"
			(at -0.5 -5.2 270)
			(layer "B.Fab")
			(effects
				(font
					(size 0.7 0.7)
					(thickness 0.15)
				)
				(justify left bottom mirror)
			)
		)
		(fp_text user "Author: Antmicro"
			(at -0.5 -4 270)
			(layer "B.Fab")
			(effects
				(font
					(size 0.7 0.7)
					(thickness 0.15)
				)
				(justify left bottom mirror)
			)
		)
		(fp_text user "${REFERENCE}"
			(at -0.5 -2.8 270)
			(layer "B.Fab")
			(effects
				(font
					(size 0.7 0.7)
					(thickness 0.15)
				)
				(justify left bottom mirror)
			)
		)
		(pad "1" smd circle
			(at 0 0 90)
			(size 1 1)
			(layers "B.Cu" "B.Mask")
			(net 777 "/Supply/DC-DC VCCINT/~{PS}")
			(pinfunction "1")
			(pintype "passive")
		)
	)
	(footprint "antmicro-footprints:R_0402_1005Metric_EIA"
		(layer "B.Cu")
		(at 193 146.5 -90)
		(descr "Resistor SMD 0402 (1005 Metric), square (rectangular) end terminal, IPC_7351 nominal, (Body size source: IPC-SM-782 page 76, https://www.pcb-3d.com/wordpress/wp-content/uploads/ipc-sm-782a_amendment_1_and_2.pdf)")
		(tags "resistor 0402")
		(property "Reference" "R130"
			(at -13.2 30.7 90)
			(layer "B.SilkS")
			(effects
				(font
					(size 0.7 0.7)
					(thickness 0.15)
				)
				(justify left bottom mirror)
			)
		)
		(property "Value" "R_1k_0402"
			(at 0 -1.169 90)
			(layer "B.Fab")
			(effects
				(font
					(size 0.7 0.7)
					(thickness 0.15)
				)
				(justify left bottom mirror)
			)
		)
		(property "Datasheet" "https://www.bourns.com/docs/product-datasheets/cr.pdf"
			(at 0 0 90)
			(layer "F.Fab")
			(hide yes)
			(effects
				(font
					(size 1.27 1.27)
					(thickness 0.15)
				)
			)
		)
		(property "MPN" "CR0402-FX-1001GLF"
			(at 0 0 270)
			(unlocked yes)
			(layer "B.Fab")
			(hide yes)
			(effects
				(font
					(size 1 1)
					(thickness 0.15)
				)
				(justify mirror)
			)
		)
		(property "Manufacturer" "Bourns"
			(at 0 0 270)
			(unlocked yes)
			(layer "B.Fab")
			(hide yes)
			(effects
				(font
					(size 1 1)
					(thickness 0.15)
				)
				(justify mirror)
			)
		)
		(property "License" "Apache-2.0"
			(at 0 0 270)
			(unlocked yes)
			(layer "B.Fab")
			(hide yes)
			(effects
				(font
					(size 1 1)
					(thickness 0.15)
				)
				(justify mirror)
			)
		)
		(property "Author" "Antmicro"
			(at 0 0 270)
			(unlocked yes)
			(layer "B.Fab")
			(hide yes)
			(effects
				(font
					(size 1 1)
					(thickness 0.15)
				)
				(justify mirror)
			)
		)
		(property "Val" "1k"
			(at 0 0 270)
			(unlocked yes)
			(layer "B.Fab")
			(hide yes)
			(effects
				(font
					(size 1 1)
					(thickness 0.15)
				)
				(justify mirror)
			)
		)
		(property "Tolerance" "1%"
			(at 0 0 270)
			(unlocked yes)
			(layer "B.Fab")
			(hide yes)
			(effects
				(font
					(size 1 1)
					(thickness 0.15)
				)
				(justify mirror)
			)
		)
		(sheetname "/FPGA banks HP/")
		(sheetfile "fpga-hp-banks.kicad_sch")
		(attr smd exclude_from_bom dnp)
		(fp_rect
			(start -0.95 0.45)
			(end 0.95 -0.45)
			(stroke
				(width 0.05)
				(type default)
			)
			(fill no)
			(layer "B.CrtYd")
		)
		(fp_line
			(start -0.5 0.25)
			(end 0.499 0.25)
			(stroke
				(width 0.15)
				(type solid)
			)
			(layer "B.Fab")
		)
		(fp_line
			(start 0.499 0.25)
			(end 0.499 -0.249)
			(stroke
				(width 0.15)
				(type solid)
			)
			(layer "B.Fab")
		)
		(fp_line
			(start -0.5 -0.249)
			(end -0.5 0.25)
			(stroke
				(width 0.15)
				(type solid)
			)
			(layer "B.Fab")
		)
		(fp_line
			(start 0.499 -0.249)
			(end -0.5 -0.249)
			(stroke
				(width 0.15)
				(type solid)
			)
			(layer "B.Fab")
		)
		(fp_text user "License: Apache-2.0"
			(at -0.95 -4.369 90)
			(layer "B.Fab")
			(effects
				(font
					(size 0.7 0.7)
					(thickness 0.15)
				)
				(justify left bottom mirror)
			)
		)
		(fp_text user "Author: Antmicro"
			(at -0.95 -5.569 90)
			(layer "B.Fab")
			(effects
				(font
					(size 0.7 0.7)
					(thickness 0.15)
				)
				(justify left bottom mirror)
			)
		)
		(fp_text user "${REFERENCE}"
			(at -0.95 -3.169 90)
			(layer "B.Fab")
			(effects
				(font
					(size 0.7 0.7)
					(thickness 0.15)
				)
				(justify left bottom mirror)
			)
		)
		(pad "1" smd roundrect
			(at -0.5 0 180)
			(size 0.6 0.6)
			(layers "B.Cu" "B.Mask" "B.Paste")
			(roundrect_rratio 0.25)
			(net 1 "GND")
			(pintype "passive")
		)
		(pad "2" smd roundrect
			(at 0.499 0 270)
			(size 0.6 0.6)
			(layers "B.Cu" "B.Mask" "B.Paste")
			(roundrect_rratio 0.25)
			(net 536 "/FPGA banks HP/VREF_65")
			(pintype "passive")
		)
	)
	(footprint "antmicro-footprints:R_0402_1005Metric"
		(layer "B.Cu")
		(at 244.86 122.225)
		(descr "Resistor SMD 0402")
		(tags "resistor SMD 0402")
		(property "Reference" "R250"
			(at -1.68 1.425 0)
			(layer "B.SilkS")
			(effects
				(font
					(size 0.7 0.7)
					(thickness 0.15)
				)
				(justify right bottom mirror)
			)
		)
		(property "Value" "R_47k_0402"
			(at -1.011843 -1.772047 0)
			(layer "B.Fab")
			(effects
				(font
					(size 0.7 0.7)
					(thickness 0.15)
				)
				(justify right bottom mirror)
			)
		)
		(property "Datasheet" "https://www.bourns.com/docs/product-datasheets/cr.pdf"
			(at 0 0 0)
			(layer "F.Fab")
			(hide yes)
			(effects
				(font
					(size 1.27 1.27)
					(thickness 0.15)
				)
			)
		)
		(property "MPN" "CR0402-FX-4702GLF"
			(at 0 0 0)
			(unlocked yes)
			(layer "B.Fab")
			(hide yes)
			(effects
				(font
					(size 1 1)
					(thickness 0.15)
				)
				(justify mirror)
			)
		)
		(property "Manufacturer" "Bourns"
			(at 0 0 0)
			(unlocked yes)
			(layer "B.Fab")
			(hide yes)
			(effects
				(font
					(size 1 1)
					(thickness 0.15)
				)
				(justify mirror)
			)
		)
		(property "License" "Apache-2.0"
			(at 0 0 0)
			(unlocked yes)
			(layer "B.Fab")
			(hide yes)
			(effects
				(font
					(size 1 1)
					(thickness 0.15)
				)
				(justify mirror)
			)
		)
		(property "Author" "Antmicro"
			(at 0 0 0)
			(unlocked yes)
			(layer "B.Fab")
			(hide yes)
			(effects
				(font
					(size 1 1)
					(thickness 0.15)
				)
				(justify mirror)
			)
		)
		(property "Val" "47k"
			(at 0 0 0)
			(unlocked yes)
			(layer "B.Fab")
			(hide yes)
			(effects
				(font
					(size 1 1)
					(thickness 0.15)
				)
				(justify mirror)
			)
		)
		(property "Tolerance" "1%"
			(at 0 0 0)
			(unlocked yes)
			(layer "B.Fab")
			(hide yes)
			(effects
				(font
					(size 1 1)
					(thickness 0.15)
				)
				(justify mirror)
			)
		)
		(sheetname "/Supply/")
		(sheetfile "supply.kicad_sch")
		(attr smd)
		(fp_rect
			(start -0.925 0.47)
			(end 0.925 -0.47)
			(stroke
				(width 0.05)
				(type default)
			)
			(fill no)
			(layer "B.CrtYd")
		)
		(fp_rect
			(start -0.5 0.25)
			(end 0.5 -0.25)
			(stroke
				(width 0.15)
				(type solid)
			)
			(fill no)
			(layer "B.Fab")
		)
		(fp_text user "License: Apache-2.0"
			(at -0.95 -5.169 180)
			(layer "B.Fab")
			(effects
				(font
					(size 0.7 0.7)
					(thickness 0.15)
				)
				(justify left bottom mirror)
			)
		)
		(fp_text user "Author: Antmicro"
			(at -0.95 -4.169 180)
			(layer "B.Fab")
			(effects
				(font
					(size 0.7 0.7)
					(thickness 0.15)
				)
				(justify left bottom mirror)
			)
		)
		(fp_text user "${REFERENCE}"
			(at -0.95 -3.168 180)
			(layer "B.Fab")
			(effects
				(font
					(size 0.7 0.7)
					(thickness 0.15)
				)
				(justify left bottom mirror)
			)
		)
		(pad "1" smd roundrect
			(at -0.48 0)
			(size 0.59 0.64)
			(layers "B.Cu" "B.Mask" "B.Paste")
			(roundrect_rratio 0.25)
			(net 1 "GND")
			(pintype "passive")
		)
		(pad "2" smd roundrect
			(at 0.48 0)
			(size 0.59 0.64)
			(layers "B.Cu" "B.Mask" "B.Paste")
			(roundrect_rratio 0.25)
			(net 812 "Heater_PWM")
			(pintype "passive")
		)
	)
)
